# S9S_MB_2U (Grand Teton) — schematic netlist excerpt (pin names and nets, part order shuffled) for the footprints in the layout excerpt that follows; sources: Cadence DE-HDL packaged netlist, KiCad conversion of 03242023_DA0F0TMBIJ0_F0T_Motherboard_J_brd_V01_OCP.brd

R2374  Q_RES  2K 1% CHIP  pkg 0402LF  page 299 : A = FM_PVPP_HBM_CPU1_EN ; B = GND
C115  Q_CAP  0.047UF 25V 10% X7R  pkg C0402  page 210 : A = P3V3_AUX_CLK_GEN_VDDMXCK_CK440 ; B = GND

(kicad_pcb
	(version 20260206)
	(generator "pcbnew")
	(generator_version "10.0")
	(general
		(thickness 1.6)
		(legacy_teardrops no)
	)
	(paper "A4")
	(title_block
		(title "03242023_DA0F0TMBIJ0_F0T_Motherboard_J_brd_V01_OCP.brd")
		(comment 1 "Grand Teton / footprints 4565-4566 of 6105")
	)
	(layers
		(0 "F.Cu" signal "TOP")
		(4 "In1.Cu" signal "GND")
		(6 "In2.Cu" signal "IN1")
		(8 "In3.Cu" signal "GND1")
		(10 "In4.Cu" signal "IN2")
		(12 "In5.Cu" signal "GND2")
		(14 "In6.Cu" signal "IN3")
		(16 "In7.Cu" signal "GND3")
		(18 "In8.Cu" signal "VCC")
		(20 "In9.Cu" signal "VCC1")
		(22 "In10.Cu" signal "GND4")
		(24 "In11.Cu" signal "IN4")
		(26 "In12.Cu" signal "GND5")
		(28 "In13.Cu" signal "IN5")
		(30 "In14.Cu" signal "GND6")
		(32 "In15.Cu" signal "IN6")
		(34 "In16.Cu" signal "GND7")
		(2 "B.Cu" signal "BOTTOM")
		(9 "F.Adhes" user "F.Adhesive")
		(11 "B.Adhes" user "B.Adhesive")
		(13 "F.Paste" user "Package Geometry/Pastemask Top")
		(15 "B.Paste" user "Package Geometry/Pastemask Bottom")
		(5 "F.SilkS" user "Ref Des/Silkscreen Top")
		(7 "B.SilkS" user "Ref Des/Silkscreen Bottom")
		(1 "F.Mask" user "Board Geometry/Soldermask Top")
		(3 "B.Mask" user "Board Geometry/Soldermask Bottom")
		(17 "Dwgs.User" user "User.Drawings")
		(19 "Cmts.User" user "User.Comments")
		(21 "Eco1.User" user "User.Eco1")
		(23 "Eco2.User" user "User.Eco2")
		(25 "Edge.Cuts" user "Board Geometry/Outline")
		(27 "Margin" user)
		(31 "F.CrtYd" user "Package Geometry/Place Bound Top")
		(29 "B.CrtYd" user "Package Geometry/Place Bound Bottom")
		(35 "F.Fab" user "Ref Des/Assembly Top")
		(33 "B.Fab" user "Ref Des/Assembly Bottom")
	)
	(footprint ""
		(layer "B.Cu")
		(at 122.157744 -354.189538)
		(property "Reference" "R2374"
			(at 0 0 0)
			(layer "B.SilkS")
			(hide yes)
			(effects
				(font
					(size 1.27 1.27)
				)
				(justify mirror)
			)
		)
		(property "Value" ""
			(at 0 0 0)
			(layer "B.Fab")
			(effects
				(font
					(size 1.27 1.27)
				)
				(justify mirror)
			)
		)
		(duplicate_pad_numbers_are_jumpers no)
		(fp_line
			(start -0.7874 -0.4064)
			(end -0.7874 0.4064)
			(stroke
				(width 0.1524)
				(type default)
			)
			(layer "B.SilkS")
		)
		(fp_line
			(start -0.7874 0.4064)
			(end 0.7874 0.4064)
			(stroke
				(width 0.1524)
				(type default)
			)
			(layer "B.SilkS")
		)
		(fp_line
			(start 0.7874 -0.4064)
			(end -0.7874 -0.4064)
			(stroke
				(width 0.1524)
				(type default)
			)
			(layer "B.SilkS")
		)
		(fp_line
			(start 0.7874 0.4064)
			(end 0.7874 -0.4064)
			(stroke
				(width 0.1524)
				(type default)
			)
			(layer "B.SilkS")
		)
		(fp_line
			(start -0.67945 -0.3048)
			(end -0.67945 0.3048)
			(stroke
				(width 0.1)
				(type default)
			)
			(layer "B.Fab")
		)
		(fp_line
			(start -0.67945 0.3048)
			(end -0.120396 0.3048)
			(stroke
				(width 0.1)
				(type default)
			)
			(layer "B.Fab")
		)
		(fp_line
			(start -0.12065 -0.3048)
			(end -0.67945 -0.3048)
			(stroke
				(width 0.1)
				(type default)
			)
			(layer "B.Fab")
		)
		(fp_line
			(start -0.12065 -0.2794)
			(end -0.12065 -0.3048)
			(stroke
				(width 0.1)
				(type default)
			)
			(layer "B.Fab")
		)
		(fp_line
			(start -0.120396 0.2794)
			(end 0.12065 0.2794)
			(stroke
				(width 0.1)
				(type default)
			)
			(layer "B.Fab")
		)
		(fp_line
			(start -0.120396 0.3048)
			(end -0.120396 0.2794)
			(stroke
				(width 0.1)
				(type default)
			)
			(layer "B.Fab")
		)
		(fp_line
			(start 0.12065 -0.305054)
			(end 0.12065 -0.2794)
			(stroke
				(width 0.1)
				(type default)
			)
			(layer "B.Fab")
		)
		(fp_line
			(start 0.12065 -0.2794)
			(end -0.12065 -0.2794)
			(stroke
				(width 0.1)
				(type default)
			)
			(layer "B.Fab")
		)
		(fp_line
			(start 0.12065 0.2794)
			(end 0.12065 0.3048)
			(stroke
				(width 0.1)
				(type default)
			)
			(layer "B.Fab")
		)
		(fp_line
			(start 0.12065 0.3048)
			(end 0.67945 0.3048)
			(stroke
				(width 0.1)
				(type default)
			)
			(layer "B.Fab")
		)
		(fp_line
			(start 0.67945 -0.305054)
			(end 0.12065 -0.305054)
			(stroke
				(width 0.1)
				(type default)
			)
			(layer "B.Fab")
		)
		(fp_line
			(start 0.67945 0.3048)
			(end 0.67945 -0.305054)
			(stroke
				(width 0.1)
				(type default)
			)
			(layer "B.Fab")
		)
		(pad "1" smd circle
			(at 0.40005 0 180)
			(size 0 0)
			(layers "B.Cu" "B.Mask" "B.Paste")
			(net "FM_PVPP_HBM_CPU1_EN")
		)
		(pad "2" smd circle
			(at -0.40005 0 180)
			(size 0 0)
			(layers "B.Cu" "B.Mask" "B.Paste")
			(net "GND")
		)
	)
	(footprint ""
		(layer "B.Cu")
		(at 258.953 -100.167948)
		(property "Reference" "C115"
			(at 0 0 0)
			(layer "B.SilkS")
			(hide yes)
			(effects
				(font
					(size 1.27 1.27)
				)
				(justify mirror)
			)
		)
		(property "Value" ""
			(at 0 0 0)
			(layer "B.Fab")
			(effects
				(font
					(size 1.27 1.27)
				)
				(justify mirror)
			)
		)
		(duplicate_pad_numbers_are_jumpers no)
		(fp_line
			(start -0.7874 -0.4064)
			(end -0.7874 0.4064)
			(stroke
				(width 0.1524)
				(type default)
			)
			(layer "B.SilkS")
		)
		(fp_line
			(start -0.7874 0.4064)
			(end 0.7874 0.4064)
			(stroke
				(width 0.1524)
				(type default)
			)
			(layer "B.SilkS")
		)
		(fp_line
			(start 0.7874 -0.4064)
			(end -0.7874 -0.4064)
			(stroke
				(width 0.1524)
				(type default)
			)
			(layer "B.SilkS")
		)
		(fp_line
			(start 0.7874 0.4064)
			(end 0.7874 -0.4064)
			(stroke
				(width 0.1524)
				(type default)
			)
			(layer "B.SilkS")
		)
		(fp_line
			(start -0.67945 -0.3048)
			(end -0.67945 0.3048)
			(stroke
				(width 0.1)
				(type default)
			)
			(layer "B.Fab")
		)
		(fp_line
			(start -0.67945 0.3048)
			(end -0.120396 0.3048)
			(stroke
				(width 0.1)
				(type default)
			)
			(layer "B.Fab")
		)
		(fp_line
			(start -0.12065 -0.3048)
			(end -0.67945 -0.3048)
			(stroke
				(width 0.1)
				(type default)
			)
			(layer "B.Fab")
		)
		(fp_line
			(start -0.12065 -0.2794)
			(end -0.12065 -0.3048)
			(stroke
				(width 0.1)
				(type default)
			)
			(layer "B.Fab")
		)
		(fp_line
			(start -0.120396 0.2794)
			(end 0.12065 0.2794)
			(stroke
				(width 0.1)
				(type default)
			)
			(layer "B.Fab")
		)
		(fp_line
			(start -0.120396 0.3048)
			(end -0.120396 0.2794)
			(stroke
				(width 0.1)
				(type default)
			)
			(layer "B.Fab")
		)
		(fp_line
			(start 0.12065 -0.305054)
			(end 0.12065 -0.2794)
			(stroke
				(width 0.1)
				(type default)
			)
			(layer "B.Fab")
		)
		(fp_line
			(start 0.12065 -0.2794)
			(end -0.12065 -0.2794)
			(stroke
				(width 0.1)
				(type default)
			)
			(layer "B.Fab")
		)
		(fp_line
			(start 0.12065 0.2794)
			(end 0.12065 0.3048)
			(stroke
				(width 0.1)
				(type default)
			)
			(layer "B.Fab")
		)
		(fp_line
			(start 0.12065 0.3048)
			(end 0.67945 0.3048)
			(stroke
				(width 0.1)
				(type default)
			)
			(layer "B.Fab")
		)
		(fp_line
			(start 0.67945 -0.305054)
			(end 0.12065 -0.305054)
			(stroke
				(width 0.1)
				(type default)
			)
			(layer "B.Fab")
		)
		(fp_line
			(start 0.67945 0.3048)
			(end 0.67945 -0.305054)
			(stroke
				(width 0.1)
				(type default)
			)
			(layer "B.Fab")
		)
		(pad "1" smd circle
			(at 0.40005 0 180)
			(size 0 0)
			(layers "B.Cu" "B.Mask" "B.Paste")
			(net "P3V3_AUX_CLK_GEN_VDDMXCK_CK440")
		)
		(pad "2" smd circle
			(at -0.40005 0 180)
			(size 0 0)
			(layers "B.Cu" "B.Mask" "B.Paste")
			(net "GND")
		)
	)
)
